# TIMECARD (Time Appliance Project (Time Card)) — schematic netlist excerpt (pin names and nets, part order shuffled) for the footprints in the layout excerpt that follows; sources: Cadence DE-HDL packaged netlist, KiCad conversion of R4006-B0001-02_R01.brd

R504  RESISTOR  4.7KOHM 1%  pkg SMC_0402R_H016  page 11 : \1\ = ANT1_IN ; \2\ = SG
R281  RESISTOR  4.7KOHM 1%  pkg SMC_0402R_H016  page 19 : \1\ = XP3R3V_FPGA ; \2\ = ICP10100_I2C_SDA

(kicad_pcb
	(version 20260206)
	(generator "pcbnew")
	(generator_version "10.0")
	(general
		(thickness 1.6)
		(legacy_teardrops no)
	)
	(paper "A4")
	(title_block
		(title "timecard-production-celestica-r4006 — R4006-B0001-02_R01.brd")
		(comment 1 "Time Appliance Project (Time Card) / footprints 932-933 of 1113")
	)
	(layers
		(0 "F.Cu" signal "TOP")
		(4 "In1.Cu" signal "L02_GND1")
		(6 "In2.Cu" signal "L03_SIG1")
		(8 "In3.Cu" signal "L04_GND2")
		(10 "In4.Cu" signal "L05_VCC1")
		(12 "In5.Cu" signal "L06_VCC2")
		(14 "In6.Cu" signal "L07_GND3")
		(16 "In7.Cu" signal "L08_SIG2")
		(18 "In8.Cu" signal "L09_GND4")
		(2 "B.Cu" signal "BOTTOM")
		(9 "F.Adhes" user "F.Adhesive")
		(11 "B.Adhes" user "B.Adhesive")
		(13 "F.Paste" user "Package Geometry/Pastemask Top")
		(15 "B.Paste" user "Package Geometry/Pastemask Bottom")
		(5 "F.SilkS" user "Ref Des/Silkscreen Top")
		(7 "B.SilkS" user "Ref Des/Silkscreen Bottom")
		(1 "F.Mask" user "Board Geometry/Soldermask Top")
		(3 "B.Mask" user "Board Geometry/Soldermask Bottom")
		(17 "Dwgs.User" user "User.Drawings")
		(19 "Cmts.User" user "User.Comments")
		(21 "Eco1.User" user "User.Eco1")
		(23 "Eco2.User" user "User.Eco2")
		(25 "Edge.Cuts" user "Board Geometry/Outline")
		(27 "Margin" user)
		(31 "F.CrtYd" user "Package Geometry/Place Bound Top")
		(29 "B.CrtYd" user "Package Geometry/Place Bound Bottom")
		(35 "F.Fab" user "Ref Des/Assembly Top")
		(33 "B.Fab" user "Ref Des/Assembly Bottom")
	)
	(footprint ""
		(layer "B.Cu")
		(at 21.59 -61.5442 -90)
		(property "Reference" "R281"
			(at 3.1242 -0.84963 270)
			(unlocked yes)
			(layer "B.SilkS")
			(effects
				(font
					(size 0.7874 0.5842)
					(thickness 0.1524)
				)
				(justify mirror)
			)
		)
		(property "Value" "VAL*"
			(at -0.02032 2.13233 270)
			(unlocked yes)
			(layer "B.Fab")
			(hide yes)
			(effects
				(font
					(size 0.7874 0.5842)
					(thickness 0.1524)
				)
				(justify mirror)
			)
		)
		(property "Tolerance" "TOL*"
			(at -0.044704 3.05435 270)
			(unlocked yes)
			(layer "Cmts.User")
			(hide yes)
			(effects
				(font
					(size 0.7874 0.5842)
					(thickness 0.1524)
				)
				(justify mirror)
			)
		)
		(property "User Part Number" "PARTNUM*"
			(at -0.02032 4.024884 270)
			(unlocked yes)
			(layer "Cmts.User")
			(hide yes)
			(effects
				(font
					(size 0.7874 0.5842)
					(thickness 0.1524)
				)
				(justify mirror)
			)
		)
		(property "Device Type" "RESISTOR-G155-14701-01,4.7KOHMA"
			(at -0.008382 1.210564 270)
			(unlocked yes)
			(layer "B.Fab")
			(hide yes)
			(effects
				(font
					(size 0.7874 0.5842)
					(thickness 0.1524)
				)
				(justify mirror)
			)
		)
		(duplicate_pad_numbers_are_jumpers no)
		(fp_line
			(start -1.143 0.5588)
			(end -1.143 -0.5588)
			(stroke
				(width 0.1)
				(type default)
			)
			(layer "B.SilkS")
		)
		(fp_line
			(start 1.143 0.5588)
			(end -1.143 0.5588)
			(stroke
				(width 0.1)
				(type default)
			)
			(layer "B.SilkS")
		)
		(fp_line
			(start -1.143 -0.5588)
			(end 1.143 -0.5588)
			(stroke
				(width 0.1)
				(type default)
			)
			(layer "B.SilkS")
		)
		(fp_line
			(start 1.143 -0.5588)
			(end 1.143 0.5588)
			(stroke
				(width 0.1)
				(type default)
			)
			(layer "B.SilkS")
		)
		(fp_poly
			(pts
				(xy 1.143 0.5588) (xy -1.143 0.5588) (xy -1.143 -0.5588) (xy 1.143 -0.5588)
			)
			(stroke
				(width 0)
				(type default)
			)
			(fill no)
			(layer "B.CrtYd")
		)
		(fp_line
			(start -0.508 0.3048)
			(end -0.508 -0.3048)
			(stroke
				(width 0.1)
				(type default)
			)
			(layer "B.Fab")
		)
		(fp_line
			(start 0.508 0.3048)
			(end -0.508 0.3048)
			(stroke
				(width 0.1)
				(type default)
			)
			(layer "B.Fab")
		)
		(fp_line
			(start -0.508 -0.3048)
			(end 0.508 -0.3048)
			(stroke
				(width 0.1)
				(type default)
			)
			(layer "B.Fab")
		)
		(fp_line
			(start 0.508 -0.3048)
			(end 0.508 0.3048)
			(stroke
				(width 0.1)
				(type default)
			)
			(layer "B.Fab")
		)
		(pad "1" smd rect
			(at 0.5334 0 90)
			(size 0.7112 0.6096)
			(layers "B.Cu" "B.Mask" "B.Paste")
			(net "XP3R3V_FPGA")
		)
		(pad "2" smd rect
			(at -0.5334 0 90)
			(size 0.7112 0.6096)
			(layers "B.Cu" "B.Mask" "B.Paste")
			(net "ICP10100_I2C_SDA")
		)
		(zone
			(layer "B.Cu")
			(hatch none 0.5)
			(connect_pads
				(clearance 0)
			)
			(min_thickness 0.25)
			(keepout
				(tracks not_allowed)
				(vias allowed)
				(pads allowed)
				(copperpour not_allowed)
				(footprints allowed)
			)
			(placement
				(enabled no)
				(sheetname "")
			)
			(fill
				(thermal_gap 0.5)
				(thermal_bridge_width 0.5)
				(island_removal_mode 0)
			)
			(polygon
				(pts
					(xy 21.2852 -61.468) (xy 21.8948 -61.468) (xy 21.8948 -61.6204) (xy 21.2852 -61.6204)
				)
			)
		)
		(zone
			(layer "B.Cu")
			(hatch none 0.5)
			(connect_pads
				(clearance 0)
			)
			(min_thickness 0.25)
			(keepout
				(tracks allowed)
				(vias not_allowed)
				(pads allowed)
				(copperpour not_allowed)
				(footprints allowed)
			)
			(placement
				(enabled no)
				(sheetname "")
			)
			(fill
				(thermal_gap 0.5)
				(thermal_bridge_width 0.5)
				(island_removal_mode 0)
			)
			(polygon
				(pts
					(xy 21.2852 -61.468) (xy 21.8948 -61.468) (xy 21.8948 -61.6204) (xy 21.2852 -61.6204)
				)
			)
		)
	)
	(footprint ""
		(layer "B.Cu")
		(at 119.847106 -54.323234 -90)
		(property "Reference" "R504"
			(at -3.461766 -0.001524 270)
			(unlocked yes)
			(layer "B.SilkS")
			(effects
				(font
					(size 0.7874 0.5842)
					(thickness 0.1524)
				)
				(justify mirror)
			)
		)
		(property "Value" "VAL*"
			(at 0 3.718306 270)
			(unlocked yes)
			(layer "B.Fab")
			(hide yes)
			(effects
				(font
					(size 0.7874 0.5842)
					(thickness 0.127)
				)
				(justify mirror)
			)
		)
		(property "Tolerance" "TOL*"
			(at 0 4.861306 270)
			(unlocked yes)
			(layer "Cmts.User")
			(hide yes)
			(effects
				(font
					(size 0.7874 0.5842)
					(thickness 0.127)
				)
				(justify mirror)
			)
		)
		(property "User Part Number" "PARTNUM*"
			(at 0 2.575306 270)
			(unlocked yes)
			(layer "Cmts.User")
			(hide yes)
			(effects
				(font
					(size 0.7874 0.5842)
					(thickness 0.127)
				)
				(justify mirror)
			)
		)
		(property "Device Type" "RESISTOR-G155-14701-01,4.7KOHMA"
			(at 0 1.432306 270)
			(unlocked yes)
			(layer "B.Fab")
			(hide yes)
			(effects
				(font
					(size 0.7874 0.5842)
					(thickness 0.127)
				)
				(justify mirror)
			)
		)
		(duplicate_pad_numbers_are_jumpers no)
		(fp_line
			(start -0.970026 0.4699)
			(end 0.970026 0.4699)
			(stroke
				(width 0.1)
				(type default)
			)
			(layer "B.SilkS")
		)
		(fp_line
			(start 0.970026 0.4699)
			(end 0.970026 -0.4699)
			(stroke
				(width 0.1)
				(type default)
			)
			(layer "B.SilkS")
		)
		(fp_line
			(start -0.970026 -0.4699)
			(end -0.970026 0.4699)
			(stroke
				(width 0.1)
				(type default)
			)
			(layer "B.SilkS")
		)
		(fp_line
			(start 0.970026 -0.4699)
			(end -0.970026 -0.4699)
			(stroke
				(width 0.1)
				(type default)
			)
			(layer "B.SilkS")
		)
		(fp_poly
			(pts
				(xy 0.970026 0.4699) (xy -0.970026 0.4699) (xy -0.970026 -0.4699) (xy 0.970026 -0.4699)
			)
			(stroke
				(width 0)
				(type default)
			)
			(fill no)
			(layer "B.CrtYd")
		)
		(fp_line
			(start -0.508 0.3048)
			(end 0.508 0.3048)
			(stroke
				(width 0.1)
				(type default)
			)
			(layer "B.Fab")
		)
		(fp_line
			(start 0.508 0.3048)
			(end 0.508 -0.3048)
			(stroke
				(width 0.1)
				(type default)
			)
			(layer "B.Fab")
		)
		(fp_line
			(start -0.508 -0.3048)
			(end -0.508 0.3048)
			(stroke
				(width 0.1)
				(type default)
			)
			(layer "B.Fab")
		)
		(fp_line
			(start 0.508 -0.3048)
			(end -0.508 -0.3048)
			(stroke
				(width 0.1)
				(type default)
			)
			(layer "B.Fab")
		)
		(pad "1" smd circle
			(at 0.500126 0 90)
			(size 0.635 0.635)
			(layers "B.Cu" "B.Mask" "B.Paste")
			(net "ANT1_IN")
		)
		(pad "2" smd circle
			(at -0.500126 0 90)
			(size 0.635 0.635)
			(layers "B.Cu" "B.Mask" "B.Paste")
			(net "SG")
		)
	)
)
